(kicad_pcb
	(version 20260206)
	(generator "pcbnew")
	(generator_version "10.0")
	(general
		(thickness 1.6)
		(legacy_teardrops no)
	)
	(paper "A4")
	(title_block
		(title "03242023_DA0F0TMBIJ0_F0T_Motherboard_J_brd_V01_OCP.brd")
		(comment 1 "Grand Teton / footprints 297-302 of 6105")
	)
	(layers
		(0 "F.Cu" signal "TOP")
		(4 "In1.Cu" signal "GND")
		(6 "In2.Cu" signal "IN1")
		(8 "In3.Cu" signal "GND1")
		(10 "In4.Cu" signal "IN2")
		(12 "In5.Cu" signal "GND2")
		(14 "In6.Cu" signal "IN3")
		(16 "In7.Cu" signal "GND3")
		(18 "In8.Cu" signal "VCC")
		(20 "In9.Cu" signal "VCC1")
		(22 "In10.Cu" signal "GND4")
		(24 "In11.Cu" signal "IN4")
		(26 "In12.Cu" signal "GND5")
		(28 "In13.Cu" signal "IN5")
		(30 "In14.Cu" signal "GND6")
		(32 "In15.Cu" signal "IN6")
		(34 "In16.Cu" signal "GND7")
		(2 "B.Cu" signal "BOTTOM")
		(9 "F.Adhes" user "F.Adhesive")
		(11 "B.Adhes" user "B.Adhesive")
		(13 "F.Paste" user "Package Geometry/Pastemask Top")
		(15 "B.Paste" user "Package Geometry/Pastemask Bottom")
		(5 "F.SilkS" user "Ref Des/Silkscreen Top")
		(7 "B.SilkS" user "Ref Des/Silkscreen Bottom")
		(1 "F.Mask" user "Board Geometry/Soldermask Top")
		(3 "B.Mask" user "Board Geometry/Soldermask Bottom")
		(17 "Dwgs.User" user "User.Drawings")
		(19 "Cmts.User" user "User.Comments")
		(21 "Eco1.User" user "User.Eco1")
		(23 "Eco2.User" user "User.Eco2")
		(25 "Edge.Cuts" user "Board Geometry/Outline")
		(27 "Margin" user)
		(31 "F.CrtYd" user "Package Geometry/Place Bound Top")
		(29 "B.CrtYd" user "Package Geometry/Place Bound Bottom")
		(35 "F.Fab" user "Ref Des/Assembly Top")
		(33 "B.Fab" user "Ref Des/Assembly Bottom")
	)
	(footprint ""
		(layer "F.Cu")
		(at 128.3843 -21.951188)
		(property "Reference" "R367"
			(at 0 0 0)
			(layer "F.SilkS")
			(hide yes)
			(effects
				(font
					(size 1.27 1.27)
				)
			)
		)
		(property "Value" ""
			(at 0 0 0)
			(layer "F.Fab")
			(effects
				(font
					(size 1.27 1.27)
				)
			)
		)
		(duplicate_pad_numbers_are_jumpers no)
		(fp_line
			(start -0.7874 -0.4064)
			(end 0.7874 -0.4064)
			(stroke
				(width 0.1524)
				(type default)
			)
			(layer "F.SilkS")
		)
		(fp_line
			(start -0.7874 0.4064)
			(end -0.7874 -0.4064)
			(stroke
				(width 0.1524)
				(type default)
			)
			(layer "F.SilkS")
		)
		(fp_line
			(start 0.7874 -0.4064)
			(end 0.7874 0.4064)
			(stroke
				(width 0.1524)
				(type default)
			)
			(layer "F.SilkS")
		)
		(fp_line
			(start 0.7874 0.4064)
			(end -0.7874 0.4064)
			(stroke
				(width 0.1524)
				(type default)
			)
			(layer "F.SilkS")
		)
		(fp_line
			(start -0.67945 -0.305054)
			(end -0.12065 -0.305054)
			(stroke
				(width 0.1)
				(type default)
			)
			(layer "F.Fab")
		)
		(fp_line
			(start -0.67945 0.3048)
			(end -0.67945 -0.305054)
			(stroke
				(width 0.1)
				(type default)
			)
			(layer "F.Fab")
		)
		(fp_line
			(start -0.12065 -0.305054)
			(end -0.12065 -0.2794)
			(stroke
				(width 0.1)
				(type default)
			)
			(layer "F.Fab")
		)
		(fp_line
			(start -0.12065 -0.2794)
			(end 0.12065 -0.2794)
			(stroke
				(width 0.1)
				(type default)
			)
			(layer "F.Fab")
		)
		(fp_line
			(start -0.12065 0.2794)
			(end -0.12065 0.3048)
			(stroke
				(width 0.1)
				(type default)
			)
			(layer "F.Fab")
		)
		(fp_line
			(start -0.12065 0.3048)
			(end -0.67945 0.3048)
			(stroke
				(width 0.1)
				(type default)
			)
			(layer "F.Fab")
		)
		(fp_line
			(start 0.120396 0.2794)
			(end -0.12065 0.2794)
			(stroke
				(width 0.1)
				(type default)
			)
			(layer "F.Fab")
		)
		(fp_line
			(start 0.120396 0.3048)
			(end 0.120396 0.2794)
			(stroke
				(width 0.1)
				(type default)
			)
			(layer "F.Fab")
		)
		(fp_line
			(start 0.12065 -0.3048)
			(end 0.67945 -0.3048)
			(stroke
				(width 0.1)
				(type default)
			)
			(layer "F.Fab")
		)
		(fp_line
			(start 0.12065 -0.2794)
			(end 0.12065 -0.3048)
			(stroke
				(width 0.1)
				(type default)
			)
			(layer "F.Fab")
		)
		(fp_line
			(start 0.67945 -0.3048)
			(end 0.67945 0.3048)
			(stroke
				(width 0.1)
				(type default)
			)
			(layer "F.Fab")
		)
		(fp_line
			(start 0.67945 0.3048)
			(end 0.120396 0.3048)
			(stroke
				(width 0.1)
				(type default)
			)
			(layer "F.Fab")
		)
		(pad "1" smd circle
			(at -0.40005 0)
			(size 0 0)
			(layers "F.Cu" "F.Mask" "F.Paste")
			(net "P3V3_AUX")
		)
		(pad "2" smd circle
			(at 0.40005 0)
			(size 0 0)
			(layers "F.Cu" "F.Mask" "F.Paste")
			(net "FM_PCH_SPKR")
		)
	)
	(footprint ""
		(layer "F.Cu")
		(at 320.190622 -55.235348)
		(property "Reference" "R401"
			(at 0 0 0)
			(layer "F.SilkS")
			(hide yes)
			(effects
				(font
					(size 1.27 1.27)
				)
			)
		)
		(property "Value" ""
			(at 0 0 0)
			(layer "F.Fab")
			(effects
				(font
					(size 1.27 1.27)
				)
			)
		)
		(duplicate_pad_numbers_are_jumpers no)
		(fp_line
			(start -0.7874 -0.4064)
			(end 0.7874 -0.4064)
			(stroke
				(width 0.1524)
				(type default)
			)
			(layer "F.SilkS")
		)
		(fp_line
			(start -0.7874 0.4064)
			(end -0.7874 -0.4064)
			(stroke
				(width 0.1524)
				(type default)
			)
			(layer "F.SilkS")
		)
		(fp_line
			(start 0.7874 -0.4064)
			(end 0.7874 0.4064)
			(stroke
				(width 0.1524)
				(type default)
			)
			(layer "F.SilkS")
		)
		(fp_line
			(start 0.7874 0.4064)
			(end -0.7874 0.4064)
			(stroke
				(width 0.1524)
				(type default)
			)
			(layer "F.SilkS")
		)
		(fp_line
			(start -0.67945 -0.305054)
			(end -0.12065 -0.305054)
			(stroke
				(width 0.1)
				(type default)
			)
			(layer "F.Fab")
		)
		(fp_line
			(start -0.67945 0.3048)
			(end -0.67945 -0.305054)
			(stroke
				(width 0.1)
				(type default)
			)
			(layer "F.Fab")
		)
		(fp_line
			(start -0.12065 -0.305054)
			(end -0.12065 -0.2794)
			(stroke
				(width 0.1)
				(type default)
			)
			(layer "F.Fab")
		)
		(fp_line
			(start -0.12065 -0.2794)
			(end 0.12065 -0.2794)
			(stroke
				(width 0.1)
				(type default)
			)
			(layer "F.Fab")
		)
		(fp_line
			(start -0.12065 0.2794)
			(end -0.12065 0.3048)
			(stroke
				(width 0.1)
				(type default)
			)
			(layer "F.Fab")
		)
		(fp_line
			(start -0.12065 0.3048)
			(end -0.67945 0.3048)
			(stroke
				(width 0.1)
				(type default)
			)
			(layer "F.Fab")
		)
		(fp_line
			(start 0.120396 0.2794)
			(end -0.12065 0.2794)
			(stroke
				(width 0.1)
				(type default)
			)
			(layer "F.Fab")
		)
		(fp_line
			(start 0.120396 0.3048)
			(end 0.120396 0.2794)
			(stroke
				(width 0.1)
				(type default)
			)
			(layer "F.Fab")
		)
		(fp_line
			(start 0.12065 -0.3048)
			(end 0.67945 -0.3048)
			(stroke
				(width 0.1)
				(type default)
			)
			(layer "F.Fab")
		)
		(fp_line
			(start 0.12065 -0.2794)
			(end 0.12065 -0.3048)
			(stroke
				(width 0.1)
				(type default)
			)
			(layer "F.Fab")
		)
		(fp_line
			(start 0.67945 -0.3048)
			(end 0.67945 0.3048)
			(stroke
				(width 0.1)
				(type default)
			)
			(layer "F.Fab")
		)
		(fp_line
			(start 0.67945 0.3048)
			(end 0.120396 0.3048)
			(stroke
				(width 0.1)
				(type default)
			)
			(layer "F.Fab")
		)
		(pad "1" smd circle
			(at -0.40005 0)
			(size 0 0)
			(layers "F.Cu" "F.Mask" "F.Paste")
			(net "P3V3_AUX")
		)
		(pad "2" smd circle
			(at 0.40005 0)
			(size 0 0)
			(layers "F.Cu" "F.Mask" "F.Paste")
			(net "IRQ_TPM_SPI_N")
		)
	)
	(footprint ""
		(layer "F.Cu")
		(at 121.521982 -324.445376)
		(property "Reference" "PL28"
			(at 7.738618 5.508498 0)
			(unlocked yes)
			(layer "F.SilkS")
			(effects
				(font
					(size 0.7874 0.5842)
					(thickness 0.1524)
				)
				(justify left)
			)
		)
		(property "Value" ""
			(at 0 0 0)
			(layer "F.Fab")
			(effects
				(font
					(size 1.27 1.27)
				)
			)
		)
		(duplicate_pad_numbers_are_jumpers no)
		(fp_line
			(start -3.750056 -5.500116)
			(end -2.393442 -5.500116)
			(stroke
				(width 0.1524)
				(type default)
			)
			(layer "F.SilkS")
		)
		(fp_line
			(start -3.750056 5.500116)
			(end -3.750056 -5.500116)
			(stroke
				(width 0.1524)
				(type default)
			)
			(layer "F.SilkS")
		)
		(fp_line
			(start -2.393442 5.500116)
			(end -3.750056 5.500116)
			(stroke
				(width 0.1524)
				(type default)
			)
			(layer "F.SilkS")
		)
		(fp_line
			(start 2.393442 5.500116)
			(end 3.750056 5.500116)
			(stroke
				(width 0.1524)
				(type default)
			)
			(layer "F.SilkS")
		)
		(fp_line
			(start 3.750056 -5.500116)
			(end 2.393442 -5.500116)
			(stroke
				(width 0.1524)
				(type default)
			)
			(layer "F.SilkS")
		)
		(fp_line
			(start 3.750056 5.500116)
			(end 3.750056 -5.500116)
			(stroke
				(width 0.1524)
				(type default)
			)
			(layer "F.SilkS")
		)
		(fp_poly
			(pts
				(xy -3.575304 -7.087362) (xy -3.216148 -6.00964) (xy -4.29387 -6.36905)
			)
			(stroke
				(width 0)
				(type default)
			)
			(fill yes)
			(layer "F.SilkS")
		)
		(fp_line
			(start -3.750056 -5.500116)
			(end -3.750056 5.500116)
			(stroke
				(width 0.1)
				(type default)
			)
			(layer "F.Fab")
		)
		(fp_line
			(start -3.750056 5.500116)
			(end 3.750056 5.500116)
			(stroke
				(width 0.1)
				(type default)
			)
			(layer "F.Fab")
		)
		(fp_line
			(start 3.750056 -5.500116)
			(end -3.750056 -5.500116)
			(stroke
				(width 0.1)
				(type default)
			)
			(layer "F.Fab")
		)
		(fp_line
			(start 3.750056 5.500116)
			(end 3.750056 -5.500116)
			(stroke
				(width 0.1)
				(type default)
			)
			(layer "F.Fab")
		)
		(fp_poly
			(pts
				(xy -4.9276 -4.757928) (xy -4.9276 -3.741928) (xy -3.9116 -4.249928)
			)
			(stroke
				(width 0)
				(type default)
			)
			(fill yes)
			(layer "F.Fab")
		)
		(pad "1" smd rect
			(at 0 -4.249928 270)
			(size 2.413 4.5212)
			(layers "F.Cu" "F.Mask" "F.Paste")
			(net "SW_PVCCIN_CPU1_SW4")
		)
		(pad "2" smd rect
			(at 0 -1.175004 270)
			(size 1.3716 4.5212)
			(layers "F.Cu" "F.Mask" "F.Paste")
			(net "IND_P1_CPL4")
		)
		(pad "3" smd rect
			(at 0 1.175004 270)
			(size 1.3716 4.5212)
			(layers "F.Cu" "F.Mask" "F.Paste")
			(net "IND_P1_CPL3")
		)
		(pad "4" smd rect
			(at 0 4.249928 270)
			(size 2.413 4.5212)
			(layers "F.Cu" "F.Mask" "F.Paste")
			(net "PVCCIN_CPU1")
		)
	)
	(footprint ""
		(layer "F.Cu")
		(at 216.065608 -408.887422)
		(property "Reference" "PR3988"
			(at 0 0 0)
			(layer "F.SilkS")
			(hide yes)
			(effects
				(font
					(size 1.27 1.27)
				)
			)
		)
		(property "Value" ""
			(at 0 0 0)
			(layer "F.Fab")
			(effects
				(font
					(size 1.27 1.27)
				)
			)
		)
		(duplicate_pad_numbers_are_jumpers no)
		(fp_line
			(start -0.7874 -0.4064)
			(end 0.7874 -0.4064)
			(stroke
				(width 0.1524)
				(type default)
			)
			(layer "F.SilkS")
		)
		(fp_line
			(start -0.7874 0.4064)
			(end -0.7874 -0.4064)
			(stroke
				(width 0.1524)
				(type default)
			)
			(layer "F.SilkS")
		)
		(fp_line
			(start 0.7874 -0.4064)
			(end 0.7874 0.4064)
			(stroke
				(width 0.1524)
				(type default)
			)
			(layer "F.SilkS")
		)
		(fp_line
			(start 0.7874 0.4064)
			(end -0.7874 0.4064)
			(stroke
				(width 0.1524)
				(type default)
			)
			(layer "F.SilkS")
		)
		(fp_line
			(start -0.67945 -0.305054)
			(end -0.12065 -0.305054)
			(stroke
				(width 0.1)
				(type default)
			)
			(layer "F.Fab")
		)
		(fp_line
			(start -0.67945 0.3048)
			(end -0.67945 -0.305054)
			(stroke
				(width 0.1)
				(type default)
			)
			(layer "F.Fab")
		)
		(fp_line
			(start -0.12065 -0.305054)
			(end -0.12065 -0.2794)
			(stroke
				(width 0.1)
				(type default)
			)
			(layer "F.Fab")
		)
		(fp_line
			(start -0.12065 -0.2794)
			(end 0.12065 -0.2794)
			(stroke
				(width 0.1)
				(type default)
			)
			(layer "F.Fab")
		)
		(fp_line
			(start -0.12065 0.2794)
			(end -0.12065 0.3048)
			(stroke
				(width 0.1)
				(type default)
			)
			(layer "F.Fab")
		)
		(fp_line
			(start -0.12065 0.3048)
			(end -0.67945 0.3048)
			(stroke
				(width 0.1)
				(type default)
			)
			(layer "F.Fab")
		)
		(fp_line
			(start 0.120396 0.2794)
			(end -0.12065 0.2794)
			(stroke
				(width 0.1)
				(type default)
			)
			(layer "F.Fab")
		)
		(fp_line
			(start 0.120396 0.3048)
			(end 0.120396 0.2794)
			(stroke
				(width 0.1)
				(type default)
			)
			(layer "F.Fab")
		)
		(fp_line
			(start 0.12065 -0.3048)
			(end 0.67945 -0.3048)
			(stroke
				(width 0.1)
				(type default)
			)
			(layer "F.Fab")
		)
		(fp_line
			(start 0.12065 -0.2794)
			(end 0.12065 -0.3048)
			(stroke
				(width 0.1)
				(type default)
			)
			(layer "F.Fab")
		)
		(fp_line
			(start 0.67945 -0.3048)
			(end 0.67945 0.3048)
			(stroke
				(width 0.1)
				(type default)
			)
			(layer "F.Fab")
		)
		(fp_line
			(start 0.67945 0.3048)
			(end 0.120396 0.3048)
			(stroke
				(width 0.1)
				(type default)
			)
			(layer "F.Fab")
		)
		(pad "1" smd circle
			(at -0.40005 0)
			(size 0 0)
			(layers "F.Cu" "F.Mask" "F.Paste")
			(net "HSC_SCREF")
		)
		(pad "2" smd circle
			(at 0.40005 0)
			(size 0 0)
			(layers "F.Cu" "F.Mask" "F.Paste")
			(net "HSC_SCREF_3")
		)
	)
	(footprint ""
		(layer "F.Cu")
		(at 388.025132 -38.265354 180)
		(property "Reference" "C580"
			(at 0 0 180)
			(layer "F.SilkS")
			(hide yes)
			(effects
				(font
					(size 1.27 1.27)
				)
			)
		)
		(property "Value" ""
			(at 0 0 180)
			(layer "F.Fab")
			(effects
				(font
					(size 1.27 1.27)
				)
			)
		)
		(duplicate_pad_numbers_are_jumpers no)
		(fp_line
			(start 0.7874 0.4064)
			(end -0.7874 0.4064)
			(stroke
				(width 0.1524)
				(type default)
			)
			(layer "F.SilkS")
		)
		(fp_line
			(start 0.7874 -0.4064)
			(end 0.7874 0.4064)
			(stroke
				(width 0.1524)
				(type default)
			)
			(layer "F.SilkS")
		)
		(fp_line
			(start -0.7874 0.4064)
			(end -0.7874 -0.4064)
			(stroke
				(width 0.1524)
				(type default)
			)
			(layer "F.SilkS")
		)
		(fp_line
			(start -0.7874 -0.4064)
			(end 0.7874 -0.4064)
			(stroke
				(width 0.1524)
				(type default)
			)
			(layer "F.SilkS")
		)
		(fp_line
			(start 0.67945 0.3048)
			(end 0.120396 0.3048)
			(stroke
				(width 0.1)
				(type default)
			)
			(layer "F.Fab")
		)
		(fp_line
			(start 0.67945 -0.3048)
			(end 0.67945 0.3048)
			(stroke
				(width 0.1)
				(type default)
			)
			(layer "F.Fab")
		)
		(fp_line
			(start 0.12065 -0.2794)
			(end 0.12065 -0.3048)
			(stroke
				(width 0.1)
				(type default)
			)
			(layer "F.Fab")
		)
		(fp_line
			(start 0.12065 -0.3048)
			(end 0.67945 -0.3048)
			(stroke
				(width 0.1)
				(type default)
			)
			(layer "F.Fab")
		)
		(fp_line
			(start 0.120396 0.3048)
			(end 0.120396 0.2794)
			(stroke
				(width 0.1)
				(type default)
			)
			(layer "F.Fab")
		)
		(fp_line
			(start 0.120396 0.2794)
			(end -0.12065 0.2794)
			(stroke
				(width 0.1)
				(type default)
			)
			(layer "F.Fab")
		)
		(fp_line
			(start -0.12065 0.3048)
			(end -0.67945 0.3048)
			(stroke
				(width 0.1)
				(type default)
			)
			(layer "F.Fab")
		)
		(fp_line
			(start -0.12065 0.2794)
			(end -0.12065 0.3048)
			(stroke
				(width 0.1)
				(type default)
			)
			(layer "F.Fab")
		)
		(fp_line
			(start -0.12065 -0.2794)
			(end 0.12065 -0.2794)
			(stroke
				(width 0.1)
				(type default)
			)
			(layer "F.Fab")
		)
		(fp_line
			(start -0.12065 -0.305054)
			(end -0.12065 -0.2794)
			(stroke
				(width 0.1)
				(type default)
			)
			(layer "F.Fab")
		)
		(fp_line
			(start -0.67945 0.3048)
			(end -0.67945 -0.305054)
			(stroke
				(width 0.1)
				(type default)
			)
			(layer "F.Fab")
		)
		(fp_line
			(start -0.67945 -0.305054)
			(end -0.12065 -0.305054)
			(stroke
				(width 0.1)
				(type default)
			)
			(layer "F.Fab")
		)
		(pad "1" smd circle
			(at -0.40005 0 180)
			(size 0 0)
			(layers "F.Cu" "F.Mask" "F.Paste")
			(net "P3V3_OCP_SFF")
		)
		(pad "2" smd circle
			(at 0.40005 0 180)
			(size 0 0)
			(layers "F.Cu" "F.Mask" "F.Paste")
			(net "GND")
		)
	)
	(footprint ""
		(layer "F.Cu")
		(at 366.48263 -260.364986 -90)
		(property "Reference" "C402"
			(at 0 0 270)
			(layer "F.SilkS")
			(hide yes)
			(effects
				(font
					(size 1.27 1.27)
				)
			)
		)
		(property "Value" ""
			(at 0 0 270)
			(layer "F.Fab")
			(effects
				(font
					(size 1.27 1.27)
				)
			)
		)
		(duplicate_pad_numbers_are_jumpers no)
		(fp_line
			(start -0.7874 0.4064)
			(end -0.7874 -0.4064)
			(stroke
				(width 0.1524)
				(type default)
			)
			(layer "F.SilkS")
		)
		(fp_line
			(start 0.7874 0.4064)
			(end -0.7874 0.4064)
			(stroke
				(width 0.1524)
				(type default)
			)
			(layer "F.SilkS")
		)
		(fp_line
			(start -0.7874 -0.4064)
			(end 0.7874 -0.4064)
			(stroke
				(width 0.1524)
				(type default)
			)
			(layer "F.SilkS")
		)
		(fp_line
			(start 0.7874 -0.4064)
			(end 0.7874 0.4064)
			(stroke
				(width 0.1524)
				(type default)
			)
			(layer "F.SilkS")
		)
		(fp_line
			(start -0.67945 0.3048)
			(end -0.67945 -0.305054)
			(stroke
				(width 0.1)
				(type default)
			)
			(layer "F.Fab")
		)
		(fp_line
			(start -0.12065 0.3048)
			(end -0.67945 0.3048)
			(stroke
				(width 0.1)
				(type default)
			)
			(layer "F.Fab")
		)
		(fp_line
			(start 0.120396 0.3048)
			(end 0.120396 0.2794)
			(stroke
				(width 0.1)
				(type default)
			)
			(layer "F.Fab")
		)
		(fp_line
			(start 0.67945 0.3048)
			(end 0.120396 0.3048)
			(stroke
				(width 0.1)
				(type default)
			)
			(layer "F.Fab")
		)
		(fp_line
			(start -0.12065 0.2794)
			(end -0.12065 0.3048)
			(stroke
				(width 0.1)
				(type default)
			)
			(layer "F.Fab")
		)
		(fp_line
			(start 0.120396 0.2794)
			(end -0.12065 0.2794)
			(stroke
				(width 0.1)
				(type default)
			)
			(layer "F.Fab")
		)
		(fp_line
			(start -0.12065 -0.2794)
			(end 0.12065 -0.2794)
			(stroke
				(width 0.1)
				(type default)
			)
			(layer "F.Fab")
		)
		(fp_line
			(start 0.12065 -0.2794)
			(end 0.12065 -0.3048)
			(stroke
				(width 0.1)
				(type default)
			)
			(layer "F.Fab")
		)
		(fp_line
			(start 0.12065 -0.3048)
			(end 0.67945 -0.3048)
			(stroke
				(width 0.1)
				(type default)
			)
			(layer "F.Fab")
		)
		(fp_line
			(start 0.67945 -0.3048)
			(end 0.67945 0.3048)
			(stroke
				(width 0.1)
				(type default)
			)
			(layer "F.Fab")
		)
		(fp_line
			(start -0.67945 -0.305054)
			(end -0.12065 -0.305054)
			(stroke
				(width 0.1)
				(type default)
			)
			(layer "F.Fab")
		)
		(fp_line
			(start -0.12065 -0.305054)
			(end -0.12065 -0.2794)
			(stroke
				(width 0.1)
				(type default)
			)
			(layer "F.Fab")
		)
		(pad "1" smd circle
			(at -0.40005 0 270)
			(size 0 0)
			(layers "F.Cu" "F.Mask" "F.Paste")
			(net "PVCCFA_EHV_FIVRA_CPU0")
		)
		(pad "2" smd circle
			(at 0.40005 0 270)
			(size 0 0)
			(layers "F.Cu" "F.Mask" "F.Paste")
			(net "GND")
		)
	)
)
